(kicad_pcb
	(version 20260206)
	(generator "pcbnew")
	(generator_version "10.0")
	(general
		(thickness 1.6)
		(legacy_teardrops no)
	)
	(paper "A4")
	(title_block
		(title "01162023_DA0F0TEBIF0_F0T_Expander_BD_F_brd_V02_OCP.brd")
		(comment 1 "Grand Teton / footprints 864-869 of 9728")
	)
	(layers
		(0 "F.Cu" signal "TOP")
		(4 "In1.Cu" signal "GND")
		(6 "In2.Cu" signal "VCC")
		(8 "In3.Cu" signal "VCC1")
		(10 "In4.Cu" signal "GND1")
		(12 "In5.Cu" signal "IN1")
		(14 "In6.Cu" signal "GND2")
		(16 "In7.Cu" signal "IN2")
		(18 "In8.Cu" signal "GND3")
		(20 "In9.Cu" signal "IN3")
		(22 "In10.Cu" signal "GND4")
		(24 "In11.Cu" signal "IN4")
		(26 "In12.Cu" signal "GND5")
		(28 "In13.Cu" signal "IN5")
		(30 "In14.Cu" signal "GND6")
		(32 "In15.Cu" signal "IN6")
		(34 "In16.Cu" signal "GND7")
		(2 "B.Cu" signal "BOTTOM")
		(9 "F.Adhes" user "F.Adhesive")
		(11 "B.Adhes" user "B.Adhesive")
		(13 "F.Paste" user "Package Geometry/Pastemask Top")
		(15 "B.Paste" user "Package Geometry/Pastemask Bottom")
		(5 "F.SilkS" user "Ref Des/Silkscreen Top")
		(7 "B.SilkS" user "Ref Des/Silkscreen Bottom")
		(1 "F.Mask" user "Board Geometry/Soldermask Top")
		(3 "B.Mask" user "Board Geometry/Soldermask Bottom")
		(17 "Dwgs.User" user "User.Drawings")
		(19 "Cmts.User" user "User.Comments")
		(21 "Eco1.User" user "User.Eco1")
		(23 "Eco2.User" user "User.Eco2")
		(25 "Edge.Cuts" user "Board Geometry/Outline")
		(27 "Margin" user)
		(31 "F.CrtYd" user "Package Geometry/Place Bound Top")
		(29 "B.CrtYd" user "Package Geometry/Place Bound Bottom")
		(35 "F.Fab" user "Ref Des/Assembly Top")
		(33 "B.Fab" user "Ref Des/Assembly Bottom")
	)
	(footprint ""
		(layer "F.Cu")
		(at 404.673816 -27.006296 -90)
		(property "Reference" "PC970"
			(at 0 0 270)
			(layer "F.SilkS")
			(hide yes)
			(effects
				(font
					(size 1.27 1.27)
				)
			)
		)
		(property "Value" ""
			(at 0 0 270)
			(layer "F.Fab")
			(effects
				(font
					(size 1.27 1.27)
				)
			)
		)
		(duplicate_pad_numbers_are_jumpers no)
		(fp_line
			(start -0.7874 0.4064)
			(end -0.7874 -0.4064)
			(stroke
				(width 0.1524)
				(type default)
			)
			(layer "F.SilkS")
		)
		(fp_line
			(start 0.7874 0.4064)
			(end -0.7874 0.4064)
			(stroke
				(width 0.1524)
				(type default)
			)
			(layer "F.SilkS")
		)
		(fp_line
			(start -0.7874 -0.4064)
			(end 0.7874 -0.4064)
			(stroke
				(width 0.1524)
				(type default)
			)
			(layer "F.SilkS")
		)
		(fp_line
			(start 0.7874 -0.4064)
			(end 0.7874 0.4064)
			(stroke
				(width 0.1524)
				(type default)
			)
			(layer "F.SilkS")
		)
		(fp_line
			(start -0.67945 0.3048)
			(end -0.67945 -0.305054)
			(stroke
				(width 0.1)
				(type default)
			)
			(layer "F.Fab")
		)
		(fp_line
			(start -0.12065 0.3048)
			(end -0.67945 0.3048)
			(stroke
				(width 0.1)
				(type default)
			)
			(layer "F.Fab")
		)
		(fp_line
			(start 0.120396 0.3048)
			(end 0.120396 0.2794)
			(stroke
				(width 0.1)
				(type default)
			)
			(layer "F.Fab")
		)
		(fp_line
			(start 0.67945 0.3048)
			(end 0.120396 0.3048)
			(stroke
				(width 0.1)
				(type default)
			)
			(layer "F.Fab")
		)
		(fp_line
			(start -0.12065 0.2794)
			(end -0.12065 0.3048)
			(stroke
				(width 0.1)
				(type default)
			)
			(layer "F.Fab")
		)
		(fp_line
			(start 0.120396 0.2794)
			(end -0.12065 0.2794)
			(stroke
				(width 0.1)
				(type default)
			)
			(layer "F.Fab")
		)
		(fp_line
			(start -0.12065 -0.2794)
			(end 0.12065 -0.2794)
			(stroke
				(width 0.1)
				(type default)
			)
			(layer "F.Fab")
		)
		(fp_line
			(start 0.12065 -0.2794)
			(end 0.12065 -0.3048)
			(stroke
				(width 0.1)
				(type default)
			)
			(layer "F.Fab")
		)
		(fp_line
			(start 0.12065 -0.3048)
			(end 0.67945 -0.3048)
			(stroke
				(width 0.1)
				(type default)
			)
			(layer "F.Fab")
		)
		(fp_line
			(start 0.67945 -0.3048)
			(end 0.67945 0.3048)
			(stroke
				(width 0.1)
				(type default)
			)
			(layer "F.Fab")
		)
		(fp_line
			(start -0.67945 -0.305054)
			(end -0.12065 -0.305054)
			(stroke
				(width 0.1)
				(type default)
			)
			(layer "F.Fab")
		)
		(fp_line
			(start -0.12065 -0.305054)
			(end -0.12065 -0.2794)
			(stroke
				(width 0.1)
				(type default)
			)
			(layer "F.Fab")
		)
		(pad "1" smd circle
			(at -0.40005 0 270)
			(size 0 0)
			(layers "F.Cu" "F.Mask" "F.Paste")
			(net "P3V3_SSD14_CO_MODE")
		)
		(pad "2" smd circle
			(at 0.40005 0 270)
			(size 0 0)
			(layers "F.Cu" "F.Mask" "F.Paste")
			(net "GND")
		)
	)
	(footprint ""
		(layer "F.Cu")
		(at 151.618442 -252.356874 -90)
		(property "Reference" "R1301"
			(at 0 0 270)
			(layer "F.SilkS")
			(hide yes)
			(effects
				(font
					(size 1.27 1.27)
				)
			)
		)
		(property "Value" ""
			(at 0 0 270)
			(layer "F.Fab")
			(effects
				(font
					(size 1.27 1.27)
				)
			)
		)
		(duplicate_pad_numbers_are_jumpers no)
		(fp_line
			(start -0.7874 0.4064)
			(end -0.7874 -0.4064)
			(stroke
				(width 0.1524)
				(type default)
			)
			(layer "F.SilkS")
		)
		(fp_line
			(start 0.7874 0.4064)
			(end -0.7874 0.4064)
			(stroke
				(width 0.1524)
				(type default)
			)
			(layer "F.SilkS")
		)
		(fp_line
			(start -0.7874 -0.4064)
			(end 0.7874 -0.4064)
			(stroke
				(width 0.1524)
				(type default)
			)
			(layer "F.SilkS")
		)
		(fp_line
			(start 0.7874 -0.4064)
			(end 0.7874 0.4064)
			(stroke
				(width 0.1524)
				(type default)
			)
			(layer "F.SilkS")
		)
		(fp_line
			(start -0.67945 0.3048)
			(end -0.67945 -0.305054)
			(stroke
				(width 0.1)
				(type default)
			)
			(layer "F.Fab")
		)
		(fp_line
			(start -0.12065 0.3048)
			(end -0.67945 0.3048)
			(stroke
				(width 0.1)
				(type default)
			)
			(layer "F.Fab")
		)
		(fp_line
			(start 0.120396 0.3048)
			(end 0.120396 0.2794)
			(stroke
				(width 0.1)
				(type default)
			)
			(layer "F.Fab")
		)
		(fp_line
			(start 0.67945 0.3048)
			(end 0.120396 0.3048)
			(stroke
				(width 0.1)
				(type default)
			)
			(layer "F.Fab")
		)
		(fp_line
			(start -0.12065 0.2794)
			(end -0.12065 0.3048)
			(stroke
				(width 0.1)
				(type default)
			)
			(layer "F.Fab")
		)
		(fp_line
			(start 0.120396 0.2794)
			(end -0.12065 0.2794)
			(stroke
				(width 0.1)
				(type default)
			)
			(layer "F.Fab")
		)
		(fp_line
			(start -0.12065 -0.2794)
			(end 0.12065 -0.2794)
			(stroke
				(width 0.1)
				(type default)
			)
			(layer "F.Fab")
		)
		(fp_line
			(start 0.12065 -0.2794)
			(end 0.12065 -0.3048)
			(stroke
				(width 0.1)
				(type default)
			)
			(layer "F.Fab")
		)
		(fp_line
			(start 0.12065 -0.3048)
			(end 0.67945 -0.3048)
			(stroke
				(width 0.1)
				(type default)
			)
			(layer "F.Fab")
		)
		(fp_line
			(start 0.67945 -0.3048)
			(end 0.67945 0.3048)
			(stroke
				(width 0.1)
				(type default)
			)
			(layer "F.Fab")
		)
		(fp_line
			(start -0.67945 -0.305054)
			(end -0.12065 -0.305054)
			(stroke
				(width 0.1)
				(type default)
			)
			(layer "F.Fab")
		)
		(fp_line
			(start -0.12065 -0.305054)
			(end -0.12065 -0.2794)
			(stroke
				(width 0.1)
				(type default)
			)
			(layer "F.Fab")
		)
		(pad "1" smd circle
			(at -0.40005 0 270)
			(size 0 0)
			(layers "F.Cu" "F.Mask" "F.Paste")
			(net "GND")
		)
		(pad "2" smd circle
			(at 0.40005 0 270)
			(size 0 0)
			(layers "F.Cu" "F.Mask" "F.Paste")
			(net "PEX1_MODE_SEL12")
		)
	)
	(footprint ""
		(layer "F.Cu")
		(at 135.642096 -198.091806 180)
		(property "Reference" "C2597"
			(at 0 0 180)
			(layer "F.SilkS")
			(hide yes)
			(effects
				(font
					(size 1.27 1.27)
				)
			)
		)
		(property "Value" ""
			(at 0 0 180)
			(layer "F.Fab")
			(effects
				(font
					(size 1.27 1.27)
				)
			)
		)
		(duplicate_pad_numbers_are_jumpers no)
		(fp_line
			(start 0.7874 0.4064)
			(end -0.7874 0.4064)
			(stroke
				(width 0.1524)
				(type default)
			)
			(layer "F.SilkS")
		)
		(fp_line
			(start 0.7874 -0.4064)
			(end 0.7874 0.4064)
			(stroke
				(width 0.1524)
				(type default)
			)
			(layer "F.SilkS")
		)
		(fp_line
			(start -0.7874 0.4064)
			(end -0.7874 -0.4064)
			(stroke
				(width 0.1524)
				(type default)
			)
			(layer "F.SilkS")
		)
		(fp_line
			(start -0.7874 -0.4064)
			(end 0.7874 -0.4064)
			(stroke
				(width 0.1524)
				(type default)
			)
			(layer "F.SilkS")
		)
		(fp_line
			(start 0.67945 0.3048)
			(end 0.120396 0.3048)
			(stroke
				(width 0.1)
				(type default)
			)
			(layer "F.Fab")
		)
		(fp_line
			(start 0.67945 -0.3048)
			(end 0.67945 0.3048)
			(stroke
				(width 0.1)
				(type default)
			)
			(layer "F.Fab")
		)
		(fp_line
			(start 0.12065 -0.2794)
			(end 0.12065 -0.3048)
			(stroke
				(width 0.1)
				(type default)
			)
			(layer "F.Fab")
		)
		(fp_line
			(start 0.12065 -0.3048)
			(end 0.67945 -0.3048)
			(stroke
				(width 0.1)
				(type default)
			)
			(layer "F.Fab")
		)
		(fp_line
			(start 0.120396 0.3048)
			(end 0.120396 0.2794)
			(stroke
				(width 0.1)
				(type default)
			)
			(layer "F.Fab")
		)
		(fp_line
			(start 0.120396 0.2794)
			(end -0.12065 0.2794)
			(stroke
				(width 0.1)
				(type default)
			)
			(layer "F.Fab")
		)
		(fp_line
			(start -0.12065 0.3048)
			(end -0.67945 0.3048)
			(stroke
				(width 0.1)
				(type default)
			)
			(layer "F.Fab")
		)
		(fp_line
			(start -0.12065 0.2794)
			(end -0.12065 0.3048)
			(stroke
				(width 0.1)
				(type default)
			)
			(layer "F.Fab")
		)
		(fp_line
			(start -0.12065 -0.2794)
			(end 0.12065 -0.2794)
			(stroke
				(width 0.1)
				(type default)
			)
			(layer "F.Fab")
		)
		(fp_line
			(start -0.12065 -0.305054)
			(end -0.12065 -0.2794)
			(stroke
				(width 0.1)
				(type default)
			)
			(layer "F.Fab")
		)
		(fp_line
			(start -0.67945 0.3048)
			(end -0.67945 -0.305054)
			(stroke
				(width 0.1)
				(type default)
			)
			(layer "F.Fab")
		)
		(fp_line
			(start -0.67945 -0.305054)
			(end -0.12065 -0.305054)
			(stroke
				(width 0.1)
				(type default)
			)
			(layer "F.Fab")
		)
		(pad "1" smd circle
			(at -0.40005 0 180)
			(size 0 0)
			(layers "F.Cu" "F.Mask" "F.Paste")
			(net "OSC_CLI_IN")
		)
		(pad "2" smd circle
			(at 0.40005 0 180)
			(size 0 0)
			(layers "F.Cu" "F.Mask" "F.Paste")
			(net "GND")
		)
	)
	(footprint ""
		(layer "F.Cu")
		(at 363.314996 -380.25578 -90)
		(property "Reference" "R6708"
			(at 0 0 270)
			(layer "F.SilkS")
			(hide yes)
			(effects
				(font
					(size 1.27 1.27)
				)
			)
		)
		(property "Value" ""
			(at 0 0 270)
			(layer "F.Fab")
			(effects
				(font
					(size 1.27 1.27)
				)
			)
		)
		(duplicate_pad_numbers_are_jumpers no)
		(fp_line
			(start -0.7874 0.4064)
			(end -0.7874 -0.4064)
			(stroke
				(width 0.1524)
				(type default)
			)
			(layer "F.SilkS")
		)
		(fp_line
			(start 0.7874 0.4064)
			(end -0.7874 0.4064)
			(stroke
				(width 0.1524)
				(type default)
			)
			(layer "F.SilkS")
		)
		(fp_line
			(start -0.7874 -0.4064)
			(end 0.7874 -0.4064)
			(stroke
				(width 0.1524)
				(type default)
			)
			(layer "F.SilkS")
		)
		(fp_line
			(start 0.7874 -0.4064)
			(end 0.7874 0.4064)
			(stroke
				(width 0.1524)
				(type default)
			)
			(layer "F.SilkS")
		)
		(fp_line
			(start -0.67945 0.3048)
			(end -0.67945 -0.305054)
			(stroke
				(width 0.1)
				(type default)
			)
			(layer "F.Fab")
		)
		(fp_line
			(start -0.12065 0.3048)
			(end -0.67945 0.3048)
			(stroke
				(width 0.1)
				(type default)
			)
			(layer "F.Fab")
		)
		(fp_line
			(start 0.120396 0.3048)
			(end 0.120396 0.2794)
			(stroke
				(width 0.1)
				(type default)
			)
			(layer "F.Fab")
		)
		(fp_line
			(start 0.67945 0.3048)
			(end 0.120396 0.3048)
			(stroke
				(width 0.1)
				(type default)
			)
			(layer "F.Fab")
		)
		(fp_line
			(start -0.12065 0.2794)
			(end -0.12065 0.3048)
			(stroke
				(width 0.1)
				(type default)
			)
			(layer "F.Fab")
		)
		(fp_line
			(start 0.120396 0.2794)
			(end -0.12065 0.2794)
			(stroke
				(width 0.1)
				(type default)
			)
			(layer "F.Fab")
		)
		(fp_line
			(start -0.12065 -0.2794)
			(end 0.12065 -0.2794)
			(stroke
				(width 0.1)
				(type default)
			)
			(layer "F.Fab")
		)
		(fp_line
			(start 0.12065 -0.2794)
			(end 0.12065 -0.3048)
			(stroke
				(width 0.1)
				(type default)
			)
			(layer "F.Fab")
		)
		(fp_line
			(start 0.12065 -0.3048)
			(end 0.67945 -0.3048)
			(stroke
				(width 0.1)
				(type default)
			)
			(layer "F.Fab")
		)
		(fp_line
			(start 0.67945 -0.3048)
			(end 0.67945 0.3048)
			(stroke
				(width 0.1)
				(type default)
			)
			(layer "F.Fab")
		)
		(fp_line
			(start -0.67945 -0.305054)
			(end -0.12065 -0.305054)
			(stroke
				(width 0.1)
				(type default)
			)
			(layer "F.Fab")
		)
		(fp_line
			(start -0.12065 -0.305054)
			(end -0.12065 -0.2794)
			(stroke
				(width 0.1)
				(type default)
			)
			(layer "F.Fab")
		)
		(pad "1" smd circle
			(at -0.40005 0 270)
			(size 0 0)
			(layers "F.Cu" "F.Mask" "F.Paste")
			(net "MB_3V3IO_RSVD4_N")
		)
		(pad "2" smd circle
			(at 0.40005 0 270)
			(size 0 0)
			(layers "F.Cu" "F.Mask" "F.Paste")
			(net "P3V3_AUX")
		)
	)
	(footprint ""
		(layer "F.Cu")
		(at 437.136032 -289.230816 90)
		(property "Reference" "R4005"
			(at 0 0 90)
			(layer "F.SilkS")
			(hide yes)
			(effects
				(font
					(size 1.27 1.27)
				)
			)
		)
		(property "Value" ""
			(at 0 0 90)
			(layer "F.Fab")
			(effects
				(font
					(size 1.27 1.27)
				)
			)
		)
		(duplicate_pad_numbers_are_jumpers no)
		(fp_line
			(start 0.7874 -0.4064)
			(end 0.7874 0.4064)
			(stroke
				(width 0.1524)
				(type default)
			)
			(layer "F.SilkS")
		)
		(fp_line
			(start -0.7874 -0.4064)
			(end 0.7874 -0.4064)
			(stroke
				(width 0.1524)
				(type default)
			)
			(layer "F.SilkS")
		)
		(fp_line
			(start 0.7874 0.4064)
			(end -0.7874 0.4064)
			(stroke
				(width 0.1524)
				(type default)
			)
			(layer "F.SilkS")
		)
		(fp_line
			(start -0.7874 0.4064)
			(end -0.7874 -0.4064)
			(stroke
				(width 0.1524)
				(type default)
			)
			(layer "F.SilkS")
		)
		(fp_line
			(start -0.12065 -0.305054)
			(end -0.12065 -0.2794)
			(stroke
				(width 0.1)
				(type default)
			)
			(layer "F.Fab")
		)
		(fp_line
			(start -0.67945 -0.305054)
			(end -0.12065 -0.305054)
			(stroke
				(width 0.1)
				(type default)
			)
			(layer "F.Fab")
		)
		(fp_line
			(start 0.67945 -0.3048)
			(end 0.67945 0.3048)
			(stroke
				(width 0.1)
				(type default)
			)
			(layer "F.Fab")
		)
		(fp_line
			(start 0.12065 -0.3048)
			(end 0.67945 -0.3048)
			(stroke
				(width 0.1)
				(type default)
			)
			(layer "F.Fab")
		)
		(fp_line
			(start 0.12065 -0.2794)
			(end 0.12065 -0.3048)
			(stroke
				(width 0.1)
				(type default)
			)
			(layer "F.Fab")
		)
		(fp_line
			(start -0.12065 -0.2794)
			(end 0.12065 -0.2794)
			(stroke
				(width 0.1)
				(type default)
			)
			(layer "F.Fab")
		)
		(fp_line
			(start 0.120396 0.2794)
			(end -0.12065 0.2794)
			(stroke
				(width 0.1)
				(type default)
			)
			(layer "F.Fab")
		)
		(fp_line
			(start -0.12065 0.2794)
			(end -0.12065 0.3048)
			(stroke
				(width 0.1)
				(type default)
			)
			(layer "F.Fab")
		)
		(fp_line
			(start 0.67945 0.3048)
			(end 0.120396 0.3048)
			(stroke
				(width 0.1)
				(type default)
			)
			(layer "F.Fab")
		)
		(fp_line
			(start 0.120396 0.3048)
			(end 0.120396 0.2794)
			(stroke
				(width 0.1)
				(type default)
			)
			(layer "F.Fab")
		)
		(fp_line
			(start -0.12065 0.3048)
			(end -0.67945 0.3048)
			(stroke
				(width 0.1)
				(type default)
			)
			(layer "F.Fab")
		)
		(fp_line
			(start -0.67945 0.3048)
			(end -0.67945 -0.305054)
			(stroke
				(width 0.1)
				(type default)
			)
			(layer "F.Fab")
		)
		(pad "1" smd circle
			(at -0.40005 0 90)
			(size 0 0)
			(layers "F.Cu" "F.Mask" "F.Paste")
			(net "SMB_PEX3_FPGA_SDA")
		)
		(pad "2" smd circle
			(at 0.40005 0 90)
			(size 0 0)
			(layers "F.Cu" "F.Mask" "F.Paste")
			(net "SMB_PEX3_HOST_LS_SDA")
		)
	)
	(footprint ""
		(layer "F.Cu")
		(at 336.042 -170.053)
		(property "Reference" "R4726"
			(at 0 0 0)
			(layer "F.SilkS")
			(hide yes)
			(effects
				(font
					(size 1.27 1.27)
				)
			)
		)
		(property "Value" ""
			(at 0 0 0)
			(layer "F.Fab")
			(effects
				(font
					(size 1.27 1.27)
				)
			)
		)
		(duplicate_pad_numbers_are_jumpers no)
		(fp_line
			(start -0.7874 -0.4064)
			(end 0.7874 -0.4064)
			(stroke
				(width 0.1524)
				(type default)
			)
			(layer "F.SilkS")
		)
		(fp_line
			(start -0.7874 0.4064)
			(end -0.7874 -0.4064)
			(stroke
				(width 0.1524)
				(type default)
			)
			(layer "F.SilkS")
		)
		(fp_line
			(start 0.7874 -0.4064)
			(end 0.7874 0.4064)
			(stroke
				(width 0.1524)
				(type default)
			)
			(layer "F.SilkS")
		)
		(fp_line
			(start 0.7874 0.4064)
			(end -0.7874 0.4064)
			(stroke
				(width 0.1524)
				(type default)
			)
			(layer "F.SilkS")
		)
		(fp_line
			(start -0.67945 -0.305054)
			(end -0.12065 -0.305054)
			(stroke
				(width 0.1)
				(type default)
			)
			(layer "F.Fab")
		)
		(fp_line
			(start -0.67945 0.3048)
			(end -0.67945 -0.305054)
			(stroke
				(width 0.1)
				(type default)
			)
			(layer "F.Fab")
		)
		(fp_line
			(start -0.12065 -0.305054)
			(end -0.12065 -0.2794)
			(stroke
				(width 0.1)
				(type default)
			)
			(layer "F.Fab")
		)
		(fp_line
			(start -0.12065 -0.2794)
			(end 0.12065 -0.2794)
			(stroke
				(width 0.1)
				(type default)
			)
			(layer "F.Fab")
		)
		(fp_line
			(start -0.12065 0.2794)
			(end -0.12065 0.3048)
			(stroke
				(width 0.1)
				(type default)
			)
			(layer "F.Fab")
		)
		(fp_line
			(start -0.12065 0.3048)
			(end -0.67945 0.3048)
			(stroke
				(width 0.1)
				(type default)
			)
			(layer "F.Fab")
		)
		(fp_line
			(start 0.120396 0.2794)
			(end -0.12065 0.2794)
			(stroke
				(width 0.1)
				(type default)
			)
			(layer "F.Fab")
		)
		(fp_line
			(start 0.120396 0.3048)
			(end 0.120396 0.2794)
			(stroke
				(width 0.1)
				(type default)
			)
			(layer "F.Fab")
		)
		(fp_line
			(start 0.12065 -0.3048)
			(end 0.67945 -0.3048)
			(stroke
				(width 0.1)
				(type default)
			)
			(layer "F.Fab")
		)
		(fp_line
			(start 0.12065 -0.2794)
			(end 0.12065 -0.3048)
			(stroke
				(width 0.1)
				(type default)
			)
			(layer "F.Fab")
		)
		(fp_line
			(start 0.67945 -0.3048)
			(end 0.67945 0.3048)
			(stroke
				(width 0.1)
				(type default)
			)
			(layer "F.Fab")
		)
		(fp_line
			(start 0.67945 0.3048)
			(end 0.120396 0.3048)
			(stroke
				(width 0.1)
				(type default)
			)
			(layer "F.Fab")
		)
		(pad "1" smd circle
			(at -0.40005 0)
			(size 0 0)
			(layers "F.Cu" "F.Mask" "F.Paste")
			(net "P3V3_AUX")
		)
		(pad "2" smd circle
			(at 0.40005 0)
			(size 0 0)
			(layers "F.Cu" "F.Mask" "F.Paste")
			(net "SSD10_PEX_PWR_EN_R")
		)
	)
)
